# BASEBOARD_FAB2 (Tioga Pass) — schematic netlist excerpt (pin names and nets, part order shuffled) for the footprints in the layout excerpt that follows; sources: Cadence DE-HDL packaged netlist, KiCad conversion of Wiwynn_Tioga_Pass_MB.brd

EU7C1  IR354XX  IR35412 IC  pkg SM  page 212
  VOS  = PVCCIO_CPU0
  LGND  = GND
  VCC  = VR_PVCCIO_CPU0_PH1_VCIN
  VDRV  = P5V_STBY
  PGND(0)  = GND
  GL(0)  = TP_PVCCIO_CPU0_GL_0
  PGND(1)  = GND
  SW  = VR_PVCCIO_CPU0_PH1_SW
  VIN(0)  = VR_FET_SW_P12V_STBY_PVCCIO_CPU0
  VIN(1)  = VR_FET_SW_P12V_STBY_PVCCIO_CPU0
  NC  = NC
  PHASE  = VR_PVCCIO_CPU0_PH1_PHASE
  BOOST  = VR_PVCCIO_CPU0_PH1_BOOT_R
  PWM  = VR_PVCCIO_CPU0_PWM1
  EN  = P5V_STBY
  TOUT_FLT  = A_TSENSE_PVCCIO_CPU0
  OCSET  = VR_PVCCIO_CPU0_OCSET
  IOUT  = ISENSE_PVCCIO_CPU0_PH1_IMON
  REFIN  = VR_PVCCIO_CPU0_AIREF1
  PGND(2)  = GND
  GL(1)  = TP_PVCCIO_CPU0_GL_1

C7A32  CAP  47UF 4V 20% X6S  pkg 0805  page 132 : A = PVNN_PCH_STBY ; B = GND

(kicad_pcb
	(version 20260206)
	(generator "pcbnew")
	(generator_version "10.0")
	(general
		(thickness 1.6)
		(legacy_teardrops no)
	)
	(paper "A4")
	(title_block
		(title "Wiwynn_Tioga_Pass_MB.brd")
		(comment 1 "Tioga Pass / footprints 2292-2293 of 4770")
	)
	(layers
		(0 "F.Cu" signal "TOP")
		(4 "In1.Cu" signal "L2GND")
		(6 "In2.Cu" signal "L3")
		(8 "In3.Cu" signal "L4GND")
		(10 "In4.Cu" signal "L5")
		(12 "In5.Cu" signal "L6GND")
		(14 "In6.Cu" signal "L7VCC")
		(16 "In7.Cu" signal "L8VCC")
		(18 "In8.Cu" signal "L9GND")
		(20 "In9.Cu" signal "L10")
		(22 "In10.Cu" signal "L11GND")
		(24 "In11.Cu" signal "L12")
		(26 "In12.Cu" signal "L13GND")
		(2 "B.Cu" signal "BOTTOM")
		(9 "F.Adhes" user "F.Adhesive")
		(11 "B.Adhes" user "B.Adhesive")
		(13 "F.Paste" user "Package Geometry/Pastemask Top")
		(15 "B.Paste" user "Package Geometry/Pastemask Bottom")
		(5 "F.SilkS" user "Ref Des/Silkscreen Top")
		(7 "B.SilkS" user "Ref Des/Silkscreen Bottom")
		(1 "F.Mask" user "Board Geometry/Soldermask Top")
		(3 "B.Mask" user "Board Geometry/Soldermask Bottom")
		(17 "Dwgs.User" user "User.Drawings")
		(19 "Cmts.User" user "User.Comments")
		(21 "Eco1.User" user "User.Eco1")
		(23 "Eco2.User" user "User.Eco2")
		(25 "Edge.Cuts" user "Board Geometry/Outline")
		(27 "Margin" user)
		(31 "F.CrtYd" user "Package Geometry/Place Bound Top")
		(29 "B.CrtYd" user "Package Geometry/Place Bound Bottom")
		(35 "F.Fab" user "Ref Des/Assembly Top")
		(33 "B.Fab" user "Ref Des/Assembly Bottom")
	)
	(footprint ""
		(layer "F.Cu")
		(at 347.032072 -97.54489 -90)
		(property "Reference" "EU7C1"
			(at 4.64566 -1.565148 0)
			(unlocked yes)
			(layer "F.SilkS")
			(effects
				(font
					(size 0.7874 0.5842)
					(thickness 0.1524)
				)
			)
		)
		(property "Value" ""
			(at 0 0 270)
			(layer "F.Fab")
			(effects
				(font
					(size 1.27 1.27)
				)
			)
		)
		(duplicate_pad_numbers_are_jumpers no)
		(fp_line
			(start -3.0099 3.429)
			(end -3.0099 -3.5052)
			(stroke
				(width 0.1524)
				(type default)
			)
			(layer "F.SilkS")
		)
		(fp_line
			(start 2.9718 3.429)
			(end -3.0099 3.429)
			(stroke
				(width 0.1524)
				(type default)
			)
			(layer "F.SilkS")
		)
		(fp_line
			(start -3.0099 -3.5052)
			(end 2.9718 -3.5052)
			(stroke
				(width 0.1524)
				(type default)
			)
			(layer "F.SilkS")
		)
		(fp_line
			(start 2.9718 -3.5052)
			(end 2.9718 3.429)
			(stroke
				(width 0.1524)
				(type default)
			)
			(layer "F.SilkS")
		)
		(fp_circle
			(center -3.057398 -2.678684)
			(end -3.057398 -2.805684)
			(stroke
				(width 0.254)
				(type default)
			)
			(fill no)
			(layer "F.SilkS")
		)
		(fp_poly
			(pts
				(xy -2.9972 -3.4925) (xy -2.9972 -2.6924) (xy -2.1971 -3.4925)
			)
			(stroke
				(width 0)
				(type default)
			)
			(fill yes)
			(layer "F.SilkS")
		)
		(fp_poly
			(pts
				(xy -2.549906 -3.050032) (xy -2.549906 3.050032) (xy 2.549906 3.050032) (xy 2.549906 -3.050032)
			)
			(stroke
				(width 0)
				(type default)
			)
			(fill no)
			(layer "F.CrtYd")
		)
		(fp_line
			(start -2.549906 3.050032)
			(end -2.549906 -3.050032)
			(stroke
				(width 0.1)
				(type default)
			)
			(layer "F.Fab")
		)
		(fp_line
			(start 2.549906 3.050032)
			(end -2.549906 3.050032)
			(stroke
				(width 0.1)
				(type default)
			)
			(layer "F.Fab")
		)
		(fp_line
			(start -2.549906 -3.050032)
			(end 2.549906 -3.050032)
			(stroke
				(width 0.1)
				(type default)
			)
			(layer "F.Fab")
		)
		(fp_line
			(start 2.549906 -3.050032)
			(end 2.549906 3.050032)
			(stroke
				(width 0.1)
				(type default)
			)
			(layer "F.Fab")
		)
		(fp_circle
			(center -3.057398 -2.678684)
			(end -3.057398 -2.805684)
			(stroke
				(width 0.254)
				(type default)
			)
			(fill no)
			(layer "F.Fab")
		)
		(pad "1" smd rect
			(at -2.39522 -2.279904 270)
			(size 0.7112 0.254)
			(layers "F.Cu" "F.Mask" "F.Paste")
			(net "PVCCIO_CPU0")
		)
		(pad "2" smd rect
			(at -2.39522 -1.83007 270)
			(size 0.7112 0.254)
			(layers "F.Cu" "F.Mask" "F.Paste")
			(net "GND")
		)
		(pad "3" smd rect
			(at -2.39522 -1.379982 270)
			(size 0.7112 0.254)
			(layers "F.Cu" "F.Mask" "F.Paste")
			(net "VR_PVCCIO_CPU0_PH1_VCIN")
		)
		(pad "4" smd rect
			(at -2.39522 -0.929894 270)
			(size 0.7112 0.254)
			(layers "F.Cu" "F.Mask" "F.Paste")
			(net "P5V_STBY")
		)
		(pad "5" smd rect
			(at -2.39522 -0.48006 270)
			(size 0.7112 0.254)
			(layers "F.Cu" "F.Mask" "F.Paste")
			(net "GND")
		)
		(pad "6" smd rect
			(at -2.39522 -0.029972 270)
			(size 0.7112 0.254)
			(layers "F.Cu" "F.Mask" "F.Paste")
			(net "TP_PVCCIO_CPU0_GL_0")
		)
		(pad "7" smd custom
			(at 0.016764 1.145032 270)
			(size 0.53975 0.53975)
			(layers "F.Cu" "F.Mask" "F.Paste")
			(net "GND")
			(options
				(clearance outline)
				(anchor circle)
			)
			(primitives
				(gr_poly
					(pts
						(xy -2.7051 1.0795) (xy -2.7051 -0.3683) (xy -0.9271 -0.3683) (xy -0.9271 -1.0795) (xy 2.7051 -1.0795)
						(xy 2.7051 1.0795)
					)
					(width 0)
					(fill yes)
				)
			)
		)
		(pad "10" smd rect
			(at -0.008382 2.874772 270)
			(size 4.3434 0.6096)
			(layers "F.Cu" "F.Mask" "F.Paste")
			(net "VR_PVCCIO_CPU0_PH1_SW")
		)
		(pad "25" smd rect
			(at 1.548384 -1.283208 270)
			(size 2.3368 2.0066)
			(layers "F.Cu" "F.Mask" "F.Paste")
			(net "VR_FET_SW_P12V_STBY_PVCCIO_CPU0")
		)
		(pad "30" smd rect
			(at 2.050034 -2.895092 270)
			(size 0.254 0.7112)
			(layers "F.Cu" "F.Mask" "F.Paste")
			(net "VR_FET_SW_P12V_STBY_PVCCIO_CPU0")
		)
		(pad "31" smd rect
			(at 1.599946 -2.895092 270)
			(size 0.254 0.7112)
			(layers "F.Cu" "F.Mask" "F.Paste")
			(net "Net_366")
		)
		(pad "32" smd rect
			(at 1.150112 -2.895092 270)
			(size 0.254 0.7112)
			(layers "F.Cu" "F.Mask" "F.Paste")
			(net "VR_PVCCIO_CPU0_PH1_PHASE")
		)
		(pad "33" smd rect
			(at 0.700024 -2.895092 270)
			(size 0.254 0.7112)
			(layers "F.Cu" "F.Mask" "F.Paste")
			(net "VR_PVCCIO_CPU0_PH1_BOOT_R")
		)
		(pad "34" smd rect
			(at 0.249936 -2.895092 270)
			(size 0.254 0.7112)
			(layers "F.Cu" "F.Mask" "F.Paste")
			(net "VR_PVCCIO_CPU0_PWM1")
		)
		(pad "35" smd rect
			(at -0.199898 -2.895092 270)
			(size 0.254 0.7112)
			(layers "F.Cu" "F.Mask" "F.Paste")
			(net "P5V_STBY")
		)
		(pad "36" smd rect
			(at -0.649986 -2.895092 270)
			(size 0.254 0.7112)
			(layers "F.Cu" "F.Mask" "F.Paste")
			(net "A_TSENSE_PVCCIO_CPU0")
		)
		(pad "37" smd rect
			(at -1.100074 -2.895092 270)
			(size 0.254 0.7112)
			(layers "F.Cu" "F.Mask" "F.Paste")
			(net "VR_PVCCIO_CPU0_OCSET")
		)
		(pad "38" smd rect
			(at -1.549908 -2.895092 270)
			(size 0.254 0.7112)
			(layers "F.Cu" "F.Mask" "F.Paste")
			(net "ISENSE_PVCCIO_CPU0_PH1_IMON")
		)
		(pad "39" smd rect
			(at -1.999996 -2.895092 270)
			(size 0.254 0.7112)
			(layers "F.Cu" "F.Mask" "F.Paste")
			(net "VR_PVCCIO_CPU0_AIREF1")
		)
		(pad "40" smd rect
			(at -0.871728 -1.283208 270)
			(size 1.8034 2.0066)
			(layers "F.Cu" "F.Mask" "F.Paste")
			(net "GND")
		)
		(pad "41" smd rect
			(at -1.533906 0.247904 270)
			(size 0.508 0.3556)
			(layers "F.Cu" "F.Mask" "F.Paste")
			(net "TP_PVCCIO_CPU0_GL_1")
		)
	)
	(footprint ""
		(layer "F.Cu")
		(at 372.6053 -137.0457)
		(property "Reference" "C7A32"
			(at 0 0 0)
			(layer "F.SilkS")
			(hide yes)
			(effects
				(font
					(size 1.27 1.27)
				)
			)
		)
		(property "Value" ""
			(at 0 0 0)
			(layer "F.Fab")
			(effects
				(font
					(size 1.27 1.27)
				)
			)
		)
		(duplicate_pad_numbers_are_jumpers no)
		(fp_rect
			(start -0.7239 1.9939)
			(end 0.7239 -0.2159)
			(stroke
				(width 0)
				(type default)
			)
			(fill no)
			(layer "F.CrtYd")
		)
		(fp_line
			(start -0.7239 -0.2159)
			(end -0.7239 1.9939)
			(stroke
				(width 0.1)
				(type default)
			)
			(layer "F.Fab")
		)
		(fp_line
			(start -0.7239 1.9939)
			(end 0.7239 1.9939)
			(stroke
				(width 0.1)
				(type default)
			)
			(layer "F.Fab")
		)
		(fp_line
			(start 0.7239 -0.2159)
			(end -0.7239 -0.2159)
			(stroke
				(width 0.1)
				(type default)
			)
			(layer "F.Fab")
		)
		(fp_line
			(start 0.7239 1.9939)
			(end 0.7239 -0.2159)
			(stroke
				(width 0.1)
				(type default)
			)
			(layer "F.Fab")
		)
		(pad "1" smd rect
			(at 0 0)
			(size 1.27 1.016)
			(layers "F.Cu" "F.Mask" "F.Paste")
			(net "PVNN_PCH_STBY")
		)
		(pad "2" smd rect
			(at 0 1.778)
			(size 1.27 1.016)
			(layers "F.Cu" "F.Mask" "F.Paste")
			(net "GND")
		)
		(zone
			(layer "F.Cu")
			(hatch none 0.5)
			(connect_pads
				(clearance 0)
			)
			(min_thickness 0.25)
			(keepout
				(tracks not_allowed)
				(vias allowed)
				(pads allowed)
				(copperpour not_allowed)
				(footprints allowed)
			)
			(placement
				(enabled no)
				(sheetname "")
			)
			(fill
				(thermal_gap 0.5)
				(thermal_bridge_width 0.5)
				(island_removal_mode 0)
			)
			(polygon
				(pts
					(xy 371.9703 -135.7757) (xy 373.2403 -135.7757) (xy 373.2403 -136.5377) (xy 371.9703 -136.5377)
				)
			)
		)
	)
)
